(kicad_pcb
	(version 20260206)
	(generator "pcbnew")
	(generator_version "10.0")
	(general
		(thickness 1.6)
		(legacy_teardrops no)
	)
	(paper "A4")
	(title_block
		(title "03242023_DA0F0TMBIJ0_F0T_Motherboard_J_brd_V01_OCP.brd")
		(comment 1 "Grand Teton / footprints 3740-3744 of 6105")
	)
	(layers
		(0 "F.Cu" signal "TOP")
		(4 "In1.Cu" signal "GND")
		(6 "In2.Cu" signal "IN1")
		(8 "In3.Cu" signal "GND1")
		(10 "In4.Cu" signal "IN2")
		(12 "In5.Cu" signal "GND2")
		(14 "In6.Cu" signal "IN3")
		(16 "In7.Cu" signal "GND3")
		(18 "In8.Cu" signal "VCC")
		(20 "In9.Cu" signal "VCC1")
		(22 "In10.Cu" signal "GND4")
		(24 "In11.Cu" signal "IN4")
		(26 "In12.Cu" signal "GND5")
		(28 "In13.Cu" signal "IN5")
		(30 "In14.Cu" signal "GND6")
		(32 "In15.Cu" signal "IN6")
		(34 "In16.Cu" signal "GND7")
		(2 "B.Cu" signal "BOTTOM")
		(9 "F.Adhes" user "F.Adhesive")
		(11 "B.Adhes" user "B.Adhesive")
		(13 "F.Paste" user "Package Geometry/Pastemask Top")
		(15 "B.Paste" user "Package Geometry/Pastemask Bottom")
		(5 "F.SilkS" user "Ref Des/Silkscreen Top")
		(7 "B.SilkS" user "Ref Des/Silkscreen Bottom")
		(1 "F.Mask" user "Board Geometry/Soldermask Top")
		(3 "B.Mask" user "Board Geometry/Soldermask Bottom")
		(17 "Dwgs.User" user "User.Drawings")
		(19 "Cmts.User" user "User.Comments")
		(21 "Eco1.User" user "User.Eco1")
		(23 "Eco2.User" user "User.Eco2")
		(25 "Edge.Cuts" user "Board Geometry/Outline")
		(27 "Margin" user)
		(31 "F.CrtYd" user "Package Geometry/Place Bound Top")
		(29 "B.CrtYd" user "Package Geometry/Place Bound Bottom")
		(35 "F.Fab" user "Ref Des/Assembly Top")
		(33 "B.Fab" user "Ref Des/Assembly Bottom")
	)
	(footprint ""
		(layer "F.Cu")
		(at 339.298534 0.383794)
		(property "Reference" "J71"
			(at -4.245864 1.013206 90)
			(unlocked yes)
			(layer "F.SilkS")
			(effects
				(font
					(size 0.7874 0.5842)
					(thickness 0.1524)
				)
				(justify left)
			)
		)
		(property "Value" ""
			(at 0 0 0)
			(layer "F.Fab")
			(effects
				(font
					(size 1.27 1.27)
				)
			)
		)
		(duplicate_pad_numbers_are_jumpers no)
		(fp_line
			(start -1.2192 -2.1082)
			(end 1.2192 -2.1082)
			(stroke
				(width 0.1524)
				(type default)
			)
			(layer "F.SilkS")
		)
		(fp_line
			(start -1.2192 2.1082)
			(end -1.2192 -2.1082)
			(stroke
				(width 0.1524)
				(type default)
			)
			(layer "F.SilkS")
		)
		(fp_line
			(start 1.2192 -2.1082)
			(end 1.2192 2.1082)
			(stroke
				(width 0.1524)
				(type default)
			)
			(layer "F.SilkS")
		)
		(fp_line
			(start 1.2192 2.1082)
			(end -1.2192 2.1082)
			(stroke
				(width 0.1524)
				(type default)
			)
			(layer "F.SilkS")
		)
		(pad "" np_thru_hole circle
			(at -2.8829 -1.27 270)
			(size 1.0414 1.0414)
			(drill 1.0414)
			(layers "*.Cu" "*.Mask")
			(clearance 0.381)
			(thermal_gap 0.381)
		)
		(pad "" np_thru_hole circle
			(at -2.8829 1.27 270)
			(size 1.0414 1.0414)
			(drill 1.0414)
			(layers "*.Cu" "*.Mask")
			(clearance 0.381)
			(thermal_gap 0.381)
		)
		(pad "" np_thru_hole circle
			(at 3.4671 -1.27 270)
			(size 1.0414 1.0414)
			(drill 1.0414)
			(layers "*.Cu" "*.Mask")
			(clearance 0.381)
			(thermal_gap 0.381)
		)
		(pad "" np_thru_hole circle
			(at 3.4671 1.27 270)
			(size 1.0414 1.0414)
			(drill 1.0414)
			(layers "*.Cu" "*.Mask")
			(clearance 0.381)
			(thermal_gap 0.381)
		)
		(pad "1" smd rect
			(at 0.8255 -0.249936 270)
			(size 0.3048 0.508)
			(layers "F.Cu" "F.Mask" "F.Paste")
			(net "DELTA_L_85_5INCH_IN1_DN")
		)
		(pad "2" smd rect
			(at 0.8255 0.249936 270)
			(size 0.3048 0.508)
			(layers "F.Cu" "F.Mask" "F.Paste")
			(net "DELTA_L_85_5INCH_IN1_DP")
		)
		(pad "3" smd circle
			(at 0 0)
			(size 0 0)
			(layers "F.Cu" "F.Mask" "F.Paste")
			(net "DELTA_L_GND_1")
		)
		(zone
			(layer "F.Cu")
			(hatch none 0.5)
			(connect_pads
				(clearance 0)
			)
			(min_thickness 0.25)
			(keepout
				(tracks not_allowed)
				(vias allowed)
				(pads allowed)
				(copperpour not_allowed)
				(footprints allowed)
			)
			(placement
				(enabled no)
				(sheetname "")
			)
			(fill
				(thermal_gap 0.5)
				(thermal_bridge_width 0.5)
				(island_removal_mode 0)
			)
			(polygon
				(pts
					(xy 340.416134 -0.164846) (xy 340.416134 -0.069342) (xy 339.819234 -0.069342) (xy 339.819234 0.337058)
					(xy 340.416134 0.337058) (xy 340.416134 0.43053) (xy 339.819234 0.43053) (xy 339.819234 0.83693)
					(xy 340.416134 0.83693) (xy 340.416134 0.932434) (xy 339.717634 0.932434) (xy 339.717634 -0.164846)
				)
			)
		)
		(zone
			(layers "F.Cu" "B.Cu" "In1.Cu" "In2.Cu" "In3.Cu" "In4.Cu" "In5.Cu" "In6.Cu"
				"In7.Cu" "In8.Cu" "In9.Cu" "In10.Cu" "In11.Cu" "In12.Cu" "In13.Cu" "In14.Cu"
				"In15.Cu" "In16.Cu"
			)
			(hatch none 0.5)
			(connect_pads
				(clearance 0)
			)
			(min_thickness 0.25)
			(keepout
				(tracks not_allowed)
				(vias allowed)
				(pads allowed)
				(copperpour not_allowed)
				(footprints allowed)
			)
			(placement
				(enabled no)
				(sheetname "")
			)
			(fill
				(thermal_gap 0.5)
				(thermal_bridge_width 0.5)
				(island_removal_mode 0)
			)
			(polygon
				(pts
					(arc
						(start 337.342734 -0.886206)
						(mid 335.488534 -0.886206)
						(end 337.342734 -0.886206)
					)
				)
			)
		)
		(zone
			(layers "F.Cu" "B.Cu" "In1.Cu" "In2.Cu" "In3.Cu" "In4.Cu" "In5.Cu" "In6.Cu"
				"In7.Cu" "In8.Cu" "In9.Cu" "In10.Cu" "In11.Cu" "In12.Cu" "In13.Cu" "In14.Cu"
				"In15.Cu" "In16.Cu"
			)
			(hatch none 0.5)
			(connect_pads
				(clearance 0)
			)
			(min_thickness 0.25)
			(keepout
				(tracks not_allowed)
				(vias allowed)
				(pads allowed)
				(copperpour not_allowed)
				(footprints allowed)
			)
			(placement
				(enabled no)
				(sheetname "")
			)
			(fill
				(thermal_gap 0.5)
				(thermal_bridge_width 0.5)
				(island_removal_mode 0)
			)
			(polygon
				(pts
					(arc
						(start 337.342734 1.653794)
						(mid 335.488534 1.653794)
						(end 337.342734 1.653794)
					)
				)
			)
		)
		(zone
			(layers "F.Cu" "B.Cu" "In1.Cu" "In2.Cu" "In3.Cu" "In4.Cu" "In5.Cu" "In6.Cu"
				"In7.Cu" "In8.Cu" "In9.Cu" "In10.Cu" "In11.Cu" "In12.Cu" "In13.Cu" "In14.Cu"
				"In15.Cu" "In16.Cu"
			)
			(hatch none 0.5)
			(connect_pads
				(clearance 0)
			)
			(min_thickness 0.25)
			(keepout
				(tracks not_allowed)
				(vias allowed)
				(pads allowed)
				(copperpour not_allowed)
				(footprints allowed)
			)
			(placement
				(enabled no)
				(sheetname "")
			)
			(fill
				(thermal_gap 0.5)
				(thermal_bridge_width 0.5)
				(island_removal_mode 0)
			)
			(polygon
				(pts
					(arc
						(start 343.692734 -0.886206)
						(mid 341.838534 -0.886206)
						(end 343.692734 -0.886206)
					)
				)
			)
		)
		(zone
			(layers "F.Cu" "B.Cu" "In1.Cu" "In2.Cu" "In3.Cu" "In4.Cu" "In5.Cu" "In6.Cu"
				"In7.Cu" "In8.Cu" "In9.Cu" "In10.Cu" "In11.Cu" "In12.Cu" "In13.Cu" "In14.Cu"
				"In15.Cu" "In16.Cu"
			)
			(hatch none 0.5)
			(connect_pads
				(clearance 0)
			)
			(min_thickness 0.25)
			(keepout
				(tracks not_allowed)
				(vias allowed)
				(pads allowed)
				(copperpour not_allowed)
				(footprints allowed)
			)
			(placement
				(enabled no)
				(sheetname "")
			)
			(fill
				(thermal_gap 0.5)
				(thermal_bridge_width 0.5)
				(island_removal_mode 0)
			)
			(polygon
				(pts
					(arc
						(start 343.692734 1.653794)
						(mid 341.838534 1.653794)
						(end 343.692734 1.653794)
					)
				)
			)
		)
	)
	(footprint ""
		(layer "F.Cu")
		(at 284.63494 -409.52928)
		(property "Reference" "R4892"
			(at 0 0 0)
			(layer "F.SilkS")
			(hide yes)
			(effects
				(font
					(size 1.27 1.27)
				)
			)
		)
		(property "Value" ""
			(at 0 0 0)
			(layer "F.Fab")
			(effects
				(font
					(size 1.27 1.27)
				)
			)
		)
		(duplicate_pad_numbers_are_jumpers no)
		(fp_line
			(start -0.7874 -0.4064)
			(end 0.7874 -0.4064)
			(stroke
				(width 0.1524)
				(type default)
			)
			(layer "F.SilkS")
		)
		(fp_line
			(start -0.7874 0.4064)
			(end -0.7874 -0.4064)
			(stroke
				(width 0.1524)
				(type default)
			)
			(layer "F.SilkS")
		)
		(fp_line
			(start 0.7874 -0.4064)
			(end 0.7874 0.4064)
			(stroke
				(width 0.1524)
				(type default)
			)
			(layer "F.SilkS")
		)
		(fp_line
			(start 0.7874 0.4064)
			(end -0.7874 0.4064)
			(stroke
				(width 0.1524)
				(type default)
			)
			(layer "F.SilkS")
		)
		(fp_line
			(start -0.67945 -0.305054)
			(end -0.12065 -0.305054)
			(stroke
				(width 0.1)
				(type default)
			)
			(layer "F.Fab")
		)
		(fp_line
			(start -0.67945 0.3048)
			(end -0.67945 -0.305054)
			(stroke
				(width 0.1)
				(type default)
			)
			(layer "F.Fab")
		)
		(fp_line
			(start -0.12065 -0.305054)
			(end -0.12065 -0.2794)
			(stroke
				(width 0.1)
				(type default)
			)
			(layer "F.Fab")
		)
		(fp_line
			(start -0.12065 -0.2794)
			(end 0.12065 -0.2794)
			(stroke
				(width 0.1)
				(type default)
			)
			(layer "F.Fab")
		)
		(fp_line
			(start -0.12065 0.2794)
			(end -0.12065 0.3048)
			(stroke
				(width 0.1)
				(type default)
			)
			(layer "F.Fab")
		)
		(fp_line
			(start -0.12065 0.3048)
			(end -0.67945 0.3048)
			(stroke
				(width 0.1)
				(type default)
			)
			(layer "F.Fab")
		)
		(fp_line
			(start 0.120396 0.2794)
			(end -0.12065 0.2794)
			(stroke
				(width 0.1)
				(type default)
			)
			(layer "F.Fab")
		)
		(fp_line
			(start 0.120396 0.3048)
			(end 0.120396 0.2794)
			(stroke
				(width 0.1)
				(type default)
			)
			(layer "F.Fab")
		)
		(fp_line
			(start 0.12065 -0.3048)
			(end 0.67945 -0.3048)
			(stroke
				(width 0.1)
				(type default)
			)
			(layer "F.Fab")
		)
		(fp_line
			(start 0.12065 -0.2794)
			(end 0.12065 -0.3048)
			(stroke
				(width 0.1)
				(type default)
			)
			(layer "F.Fab")
		)
		(fp_line
			(start 0.67945 -0.3048)
			(end 0.67945 0.3048)
			(stroke
				(width 0.1)
				(type default)
			)
			(layer "F.Fab")
		)
		(fp_line
			(start 0.67945 0.3048)
			(end 0.120396 0.3048)
			(stroke
				(width 0.1)
				(type default)
			)
			(layer "F.Fab")
		)
		(pad "1" smd circle
			(at -0.40005 0)
			(size 0 0)
			(layers "F.Cu" "F.Mask" "F.Paste")
			(net "P12V_HSC_TEMP_R")
		)
		(pad "2" smd circle
			(at 0.40005 0)
			(size 0 0)
			(layers "F.Cu" "F.Mask" "F.Paste")
			(net "P12V_HSC_TEMP_D+")
		)
	)
	(footprint ""
		(layer "F.Cu")
		(at 418.485828 -165.760654)
		(property "Reference" "PC633"
			(at 0 0 0)
			(layer "F.SilkS")
			(hide yes)
			(effects
				(font
					(size 1.27 1.27)
				)
			)
		)
		(property "Value" ""
			(at 0 0 0)
			(layer "F.Fab")
			(effects
				(font
					(size 1.27 1.27)
				)
			)
		)
		(duplicate_pad_numbers_are_jumpers no)
		(fp_line
			(start -0.7874 -0.4064)
			(end 0.7874 -0.4064)
			(stroke
				(width 0.1524)
				(type default)
			)
			(layer "F.SilkS")
		)
		(fp_line
			(start -0.7874 0.4064)
			(end -0.7874 -0.4064)
			(stroke
				(width 0.1524)
				(type default)
			)
			(layer "F.SilkS")
		)
		(fp_line
			(start 0.7874 -0.4064)
			(end 0.7874 0.4064)
			(stroke
				(width 0.1524)
				(type default)
			)
			(layer "F.SilkS")
		)
		(fp_line
			(start 0.7874 0.4064)
			(end -0.7874 0.4064)
			(stroke
				(width 0.1524)
				(type default)
			)
			(layer "F.SilkS")
		)
		(fp_line
			(start -0.67945 -0.305054)
			(end -0.12065 -0.305054)
			(stroke
				(width 0.1)
				(type default)
			)
			(layer "F.Fab")
		)
		(fp_line
			(start -0.67945 0.3048)
			(end -0.67945 -0.305054)
			(stroke
				(width 0.1)
				(type default)
			)
			(layer "F.Fab")
		)
		(fp_line
			(start -0.12065 -0.305054)
			(end -0.12065 -0.2794)
			(stroke
				(width 0.1)
				(type default)
			)
			(layer "F.Fab")
		)
		(fp_line
			(start -0.12065 -0.2794)
			(end 0.12065 -0.2794)
			(stroke
				(width 0.1)
				(type default)
			)
			(layer "F.Fab")
		)
		(fp_line
			(start -0.12065 0.2794)
			(end -0.12065 0.3048)
			(stroke
				(width 0.1)
				(type default)
			)
			(layer "F.Fab")
		)
		(fp_line
			(start -0.12065 0.3048)
			(end -0.67945 0.3048)
			(stroke
				(width 0.1)
				(type default)
			)
			(layer "F.Fab")
		)
		(fp_line
			(start 0.120396 0.2794)
			(end -0.12065 0.2794)
			(stroke
				(width 0.1)
				(type default)
			)
			(layer "F.Fab")
		)
		(fp_line
			(start 0.120396 0.3048)
			(end 0.120396 0.2794)
			(stroke
				(width 0.1)
				(type default)
			)
			(layer "F.Fab")
		)
		(fp_line
			(start 0.12065 -0.3048)
			(end 0.67945 -0.3048)
			(stroke
				(width 0.1)
				(type default)
			)
			(layer "F.Fab")
		)
		(fp_line
			(start 0.12065 -0.2794)
			(end 0.12065 -0.3048)
			(stroke
				(width 0.1)
				(type default)
			)
			(layer "F.Fab")
		)
		(fp_line
			(start 0.67945 -0.3048)
			(end 0.67945 0.3048)
			(stroke
				(width 0.1)
				(type default)
			)
			(layer "F.Fab")
		)
		(fp_line
			(start 0.67945 0.3048)
			(end 0.120396 0.3048)
			(stroke
				(width 0.1)
				(type default)
			)
			(layer "F.Fab")
		)
		(pad "1" smd circle
			(at -0.40005 0)
			(size 0 0)
			(layers "F.Cu" "F.Mask" "F.Paste")
			(net "PVCCD_HV_CPU0_VDD1")
		)
		(pad "2" smd circle
			(at 0.40005 0)
			(size 0 0)
			(layers "F.Cu" "F.Mask" "F.Paste")
			(net "GND")
		)
	)
	(footprint ""
		(layer "F.Cu")
		(at 437.875172 -29.684218 180)
		(property "Reference" "PR3839"
			(at 0 0 180)
			(layer "F.SilkS")
			(hide yes)
			(effects
				(font
					(size 1.27 1.27)
				)
			)
		)
		(property "Value" ""
			(at 0 0 180)
			(layer "F.Fab")
			(effects
				(font
					(size 1.27 1.27)
				)
			)
		)
		(duplicate_pad_numbers_are_jumpers no)
		(fp_line
			(start 0.7874 0.4064)
			(end -0.7874 0.4064)
			(stroke
				(width 0.1524)
				(type default)
			)
			(layer "F.SilkS")
		)
		(fp_line
			(start 0.7874 -0.4064)
			(end 0.7874 0.4064)
			(stroke
				(width 0.1524)
				(type default)
			)
			(layer "F.SilkS")
		)
		(fp_line
			(start -0.7874 0.4064)
			(end -0.7874 -0.4064)
			(stroke
				(width 0.1524)
				(type default)
			)
			(layer "F.SilkS")
		)
		(fp_line
			(start -0.7874 -0.4064)
			(end 0.7874 -0.4064)
			(stroke
				(width 0.1524)
				(type default)
			)
			(layer "F.SilkS")
		)
		(fp_line
			(start 0.67945 0.3048)
			(end 0.120396 0.3048)
			(stroke
				(width 0.1)
				(type default)
			)
			(layer "F.Fab")
		)
		(fp_line
			(start 0.67945 -0.3048)
			(end 0.67945 0.3048)
			(stroke
				(width 0.1)
				(type default)
			)
			(layer "F.Fab")
		)
		(fp_line
			(start 0.12065 -0.2794)
			(end 0.12065 -0.3048)
			(stroke
				(width 0.1)
				(type default)
			)
			(layer "F.Fab")
		)
		(fp_line
			(start 0.12065 -0.3048)
			(end 0.67945 -0.3048)
			(stroke
				(width 0.1)
				(type default)
			)
			(layer "F.Fab")
		)
		(fp_line
			(start 0.120396 0.3048)
			(end 0.120396 0.2794)
			(stroke
				(width 0.1)
				(type default)
			)
			(layer "F.Fab")
		)
		(fp_line
			(start 0.120396 0.2794)
			(end -0.12065 0.2794)
			(stroke
				(width 0.1)
				(type default)
			)
			(layer "F.Fab")
		)
		(fp_line
			(start -0.12065 0.3048)
			(end -0.67945 0.3048)
			(stroke
				(width 0.1)
				(type default)
			)
			(layer "F.Fab")
		)
		(fp_line
			(start -0.12065 0.2794)
			(end -0.12065 0.3048)
			(stroke
				(width 0.1)
				(type default)
			)
			(layer "F.Fab")
		)
		(fp_line
			(start -0.12065 -0.2794)
			(end 0.12065 -0.2794)
			(stroke
				(width 0.1)
				(type default)
			)
			(layer "F.Fab")
		)
		(fp_line
			(start -0.12065 -0.305054)
			(end -0.12065 -0.2794)
			(stroke
				(width 0.1)
				(type default)
			)
			(layer "F.Fab")
		)
		(fp_line
			(start -0.67945 0.3048)
			(end -0.67945 -0.305054)
			(stroke
				(width 0.1)
				(type default)
			)
			(layer "F.Fab")
		)
		(fp_line
			(start -0.67945 -0.305054)
			(end -0.12065 -0.305054)
			(stroke
				(width 0.1)
				(type default)
			)
			(layer "F.Fab")
		)
		(pad "1" smd circle
			(at -0.40005 0 180)
			(size 0 0)
			(layers "F.Cu" "F.Mask" "F.Paste")
			(net "P12V_OCP_FLTB_1")
		)
		(pad "2" smd circle
			(at 0.40005 0 180)
			(size 0 0)
			(layers "F.Cu" "F.Mask" "F.Paste")
			(net "P3V3_AUX")
		)
	)
	(footprint ""
		(layer "F.Cu")
		(at 317.396622 -51.196748)
		(property "Reference" "R3041"
			(at 0 0 0)
			(layer "F.SilkS")
			(hide yes)
			(effects
				(font
					(size 1.27 1.27)
				)
			)
		)
		(property "Value" ""
			(at 0 0 0)
			(layer "F.Fab")
			(effects
				(font
					(size 1.27 1.27)
				)
			)
		)
		(duplicate_pad_numbers_are_jumpers no)
		(fp_line
			(start -0.7874 -0.4064)
			(end 0.7874 -0.4064)
			(stroke
				(width 0.1524)
				(type default)
			)
			(layer "F.SilkS")
		)
		(fp_line
			(start -0.7874 0.4064)
			(end -0.7874 -0.4064)
			(stroke
				(width 0.1524)
				(type default)
			)
			(layer "F.SilkS")
		)
		(fp_line
			(start 0.7874 -0.4064)
			(end 0.7874 0.4064)
			(stroke
				(width 0.1524)
				(type default)
			)
			(layer "F.SilkS")
		)
		(fp_line
			(start 0.7874 0.4064)
			(end -0.7874 0.4064)
			(stroke
				(width 0.1524)
				(type default)
			)
			(layer "F.SilkS")
		)
		(fp_line
			(start -0.67945 -0.305054)
			(end -0.12065 -0.305054)
			(stroke
				(width 0.1)
				(type default)
			)
			(layer "F.Fab")
		)
		(fp_line
			(start -0.67945 0.3048)
			(end -0.67945 -0.305054)
			(stroke
				(width 0.1)
				(type default)
			)
			(layer "F.Fab")
		)
		(fp_line
			(start -0.12065 -0.305054)
			(end -0.12065 -0.2794)
			(stroke
				(width 0.1)
				(type default)
			)
			(layer "F.Fab")
		)
		(fp_line
			(start -0.12065 -0.2794)
			(end 0.12065 -0.2794)
			(stroke
				(width 0.1)
				(type default)
			)
			(layer "F.Fab")
		)
		(fp_line
			(start -0.12065 0.2794)
			(end -0.12065 0.3048)
			(stroke
				(width 0.1)
				(type default)
			)
			(layer "F.Fab")
		)
		(fp_line
			(start -0.12065 0.3048)
			(end -0.67945 0.3048)
			(stroke
				(width 0.1)
				(type default)
			)
			(layer "F.Fab")
		)
		(fp_line
			(start 0.120396 0.2794)
			(end -0.12065 0.2794)
			(stroke
				(width 0.1)
				(type default)
			)
			(layer "F.Fab")
		)
		(fp_line
			(start 0.120396 0.3048)
			(end 0.120396 0.2794)
			(stroke
				(width 0.1)
				(type default)
			)
			(layer "F.Fab")
		)
		(fp_line
			(start 0.12065 -0.3048)
			(end 0.67945 -0.3048)
			(stroke
				(width 0.1)
				(type default)
			)
			(layer "F.Fab")
		)
		(fp_line
			(start 0.12065 -0.2794)
			(end 0.12065 -0.3048)
			(stroke
				(width 0.1)
				(type default)
			)
			(layer "F.Fab")
		)
		(fp_line
			(start 0.67945 -0.3048)
			(end 0.67945 0.3048)
			(stroke
				(width 0.1)
				(type default)
			)
			(layer "F.Fab")
		)
		(fp_line
			(start 0.67945 0.3048)
			(end 0.120396 0.3048)
			(stroke
				(width 0.1)
				(type default)
			)
			(layer "F.Fab")
		)
		(pad "1" smd circle
			(at -0.40005 0)
			(size 0 0)
			(layers "F.Cu" "F.Mask" "F.Paste")
			(net "P3V3_AUX")
		)
		(pad "2" smd circle
			(at 0.40005 0)
			(size 0 0)
			(layers "F.Cu" "F.Mask" "F.Paste")
			(net "FM_PCH_GLB_RST_WARN_N")
		)
	)
)
